(kicad_pcb
	(version 20260206)
	(generator "pcbnew")
	(generator_version "10.0")
	(general
		(thickness 1.6)
		(legacy_teardrops no)
	)
	(paper "A4")
	(title_block
		(title "Wiwynn_Tioga_Pass_MB.brd")
		(comment 1 "Tioga Pass / footprints 1358-1364 of 4770")
	)
	(layers
		(0 "F.Cu" signal "TOP")
		(4 "In1.Cu" signal "L2GND")
		(6 "In2.Cu" signal "L3")
		(8 "In3.Cu" signal "L4GND")
		(10 "In4.Cu" signal "L5")
		(12 "In5.Cu" signal "L6GND")
		(14 "In6.Cu" signal "L7VCC")
		(16 "In7.Cu" signal "L8VCC")
		(18 "In8.Cu" signal "L9GND")
		(20 "In9.Cu" signal "L10")
		(22 "In10.Cu" signal "L11GND")
		(24 "In11.Cu" signal "L12")
		(26 "In12.Cu" signal "L13GND")
		(2 "B.Cu" signal "BOTTOM")
		(9 "F.Adhes" user "F.Adhesive")
		(11 "B.Adhes" user "B.Adhesive")
		(13 "F.Paste" user "Package Geometry/Pastemask Top")
		(15 "B.Paste" user "Package Geometry/Pastemask Bottom")
		(5 "F.SilkS" user "Ref Des/Silkscreen Top")
		(7 "B.SilkS" user "Ref Des/Silkscreen Bottom")
		(1 "F.Mask" user "Board Geometry/Soldermask Top")
		(3 "B.Mask" user "Board Geometry/Soldermask Bottom")
		(17 "Dwgs.User" user "User.Drawings")
		(19 "Cmts.User" user "User.Comments")
		(21 "Eco1.User" user "User.Eco1")
		(23 "Eco2.User" user "User.Eco2")
		(25 "Edge.Cuts" user "Board Geometry/Outline")
		(27 "Margin" user)
		(31 "F.CrtYd" user "Package Geometry/Place Bound Top")
		(29 "B.CrtYd" user "Package Geometry/Place Bound Bottom")
		(35 "F.Fab" user "Ref Des/Assembly Top")
		(33 "B.Fab" user "Ref Des/Assembly Bottom")
	)
	(footprint ""
		(layer "F.Cu")
		(at 378.254768 -32.3215 90)
		(property "Reference" "C8F11"
			(at -0.8382 -0.67818 90)
			(unlocked yes)
			(layer "F.SilkS")
			(effects
				(font
					(size 0.4064 0.254)
					(thickness 0.1524)
				)
				(justify left)
			)
		)
		(property "Value" ""
			(at 0 0 90)
			(layer "F.Fab")
			(effects
				(font
					(size 1.27 1.27)
				)
			)
		)
		(duplicate_pad_numbers_are_jumpers no)
		(fp_poly
			(pts
				(xy 0.3048 -0.1016) (xy 0.3048 0.9906) (xy -0.3048 0.9906) (xy -0.3048 -0.1016)
			)
			(stroke
				(width 0)
				(type default)
			)
			(fill no)
			(layer "F.CrtYd")
		)
		(fp_line
			(start 0.3048 -0.1016)
			(end -0.3048 -0.1016)
			(stroke
				(width 0.1)
				(type default)
			)
			(layer "F.Fab")
		)
		(fp_line
			(start -0.3048 -0.1016)
			(end -0.3048 0.9906)
			(stroke
				(width 0.1)
				(type default)
			)
			(layer "F.Fab")
		)
		(fp_line
			(start 0.3048 0.9906)
			(end 0.3048 -0.1016)
			(stroke
				(width 0.1)
				(type default)
			)
			(layer "F.Fab")
		)
		(fp_line
			(start -0.3048 0.9906)
			(end 0.3048 0.9906)
			(stroke
				(width 0.1)
				(type default)
			)
			(layer "F.Fab")
		)
		(pad "1" smd rect
			(at 0 0 90)
			(size 0.508 0.508)
			(layers "F.Cu" "F.Mask" "F.Paste")
			(net "SATA6G_S0_TX_DN")
		)
		(pad "2" smd rect
			(at 0 0.889 90)
			(size 0.508 0.508)
			(layers "F.Cu" "F.Mask" "F.Paste")
			(net "P3E_PCH_M2_SATA6G_TX_R_DN")
		)
		(zone
			(layer "F.Cu")
			(hatch none 0.5)
			(connect_pads
				(clearance 0)
			)
			(min_thickness 0.25)
			(keepout
				(tracks allowed)
				(vias not_allowed)
				(pads allowed)
				(copperpour not_allowed)
				(footprints allowed)
			)
			(placement
				(enabled no)
				(sheetname "")
			)
			(fill
				(thermal_gap 0.5)
				(thermal_bridge_width 0.5)
				(island_removal_mode 0)
			)
			(polygon
				(pts
					(xy 378.508768 -32.0675) (xy 378.508768 -32.5755) (xy 378.889768 -32.5755) (xy 378.889768 -32.0675)
				)
			)
		)
		(zone
			(layer "F.Cu")
			(hatch none 0.5)
			(connect_pads
				(clearance 0)
			)
			(min_thickness 0.25)
			(keepout
				(tracks not_allowed)
				(vias allowed)
				(pads allowed)
				(copperpour not_allowed)
				(footprints allowed)
			)
			(placement
				(enabled no)
				(sheetname "")
			)
			(fill
				(thermal_gap 0.5)
				(thermal_bridge_width 0.5)
				(island_removal_mode 0)
			)
			(polygon
				(pts
					(xy 378.889768 -32.0675) (xy 378.889768 -32.5755) (xy 378.508768 -32.5755) (xy 378.508768 -32.0675)
				)
			)
		)
	)
	(footprint ""
		(layer "F.Cu")
		(at 17.91335 -118.145052 180)
		(property "Reference" "C1B15"
			(at 0 0 180)
			(layer "F.SilkS")
			(hide yes)
			(effects
				(font
					(size 1.27 1.27)
				)
			)
		)
		(property "Value" ""
			(at 0 0 180)
			(layer "F.Fab")
			(effects
				(font
					(size 1.27 1.27)
				)
			)
		)
		(duplicate_pad_numbers_are_jumpers no)
		(fp_rect
			(start 0.3048 -0.1016)
			(end -0.3048 0.9906)
			(stroke
				(width 0)
				(type default)
			)
			(fill no)
			(layer "F.CrtYd")
		)
		(fp_line
			(start 0.3048 0.9906)
			(end 0.3048 -0.1016)
			(stroke
				(width 0.1)
				(type default)
			)
			(layer "F.Fab")
		)
		(fp_line
			(start 0.3048 -0.1016)
			(end -0.3048 -0.1016)
			(stroke
				(width 0.1)
				(type default)
			)
			(layer "F.Fab")
		)
		(fp_line
			(start -0.3048 0.9906)
			(end 0.3048 0.9906)
			(stroke
				(width 0.1)
				(type default)
			)
			(layer "F.Fab")
		)
		(fp_line
			(start -0.3048 -0.1016)
			(end -0.3048 0.9906)
			(stroke
				(width 0.1)
				(type default)
			)
			(layer "F.Fab")
		)
		(pad "1" smd rect
			(at 0 0 180)
			(size 0.508 0.508)
			(layers "F.Cu" "F.Mask" "F.Paste")
			(net "FAN_TACH2")
		)
		(pad "2" smd rect
			(at 0 0.889 180)
			(size 0.508 0.508)
			(layers "F.Cu" "F.Mask" "F.Paste")
			(net "GND")
		)
		(zone
			(layer "F.Cu")
			(hatch none 0.5)
			(connect_pads
				(clearance 0)
			)
			(min_thickness 0.25)
			(keepout
				(tracks allowed)
				(vias not_allowed)
				(pads allowed)
				(copperpour not_allowed)
				(footprints allowed)
			)
			(placement
				(enabled no)
				(sheetname "")
			)
			(fill
				(thermal_gap 0.5)
				(thermal_bridge_width 0.5)
				(island_removal_mode 0)
			)
			(polygon
				(pts
					(xy 17.65935 -118.399052) (xy 18.16735 -118.399052) (xy 18.16735 -118.780052) (xy 17.65935 -118.780052)
				)
			)
		)
		(zone
			(layer "F.Cu")
			(hatch none 0.5)
			(connect_pads
				(clearance 0)
			)
			(min_thickness 0.25)
			(keepout
				(tracks not_allowed)
				(vias allowed)
				(pads allowed)
				(copperpour not_allowed)
				(footprints allowed)
			)
			(placement
				(enabled no)
				(sheetname "")
			)
			(fill
				(thermal_gap 0.5)
				(thermal_bridge_width 0.5)
				(island_removal_mode 0)
			)
			(polygon
				(pts
					(xy 17.65935 -118.399052) (xy 18.16735 -118.399052) (xy 18.16735 -118.780052) (xy 17.65935 -118.780052)
				)
			)
		)
	)
	(footprint ""
		(layer "F.Cu")
		(at 417.5506 -18.7452)
		(property "Reference" "R1U11"
			(at 0 0 0)
			(layer "F.SilkS")
			(hide yes)
			(effects
				(font
					(size 1.27 1.27)
				)
			)
		)
		(property "Value" ""
			(at 0 0 0)
			(layer "F.Fab")
			(effects
				(font
					(size 1.27 1.27)
				)
			)
		)
		(duplicate_pad_numbers_are_jumpers no)
		(fp_poly
			(pts
				(xy -0.2794 -0.1016) (xy 0.2794 -0.1016) (xy 0.2794 0.9906) (xy -0.2794 0.9906)
			)
			(stroke
				(width 0)
				(type default)
			)
			(fill no)
			(layer "F.CrtYd")
		)
		(fp_line
			(start -0.2794 -0.1016)
			(end -0.2794 0.9906)
			(stroke
				(width 0.1)
				(type default)
			)
			(layer "F.Fab")
		)
		(fp_line
			(start -0.2794 0.9906)
			(end 0.2794 0.9906)
			(stroke
				(width 0.1)
				(type default)
			)
			(layer "F.Fab")
		)
		(fp_line
			(start 0.2794 -0.1016)
			(end -0.2794 -0.1016)
			(stroke
				(width 0.1)
				(type default)
			)
			(layer "F.Fab")
		)
		(fp_line
			(start 0.2794 0.9906)
			(end 0.2794 -0.1016)
			(stroke
				(width 0.1)
				(type default)
			)
			(layer "F.Fab")
		)
		(pad "1" smd rect
			(at 0 0)
			(size 0.508 0.508)
			(layers "F.Cu" "F.Mask" "F.Paste")
			(net "SMB_VR_STBY_LVC3_SCL_R")
		)
		(pad "2" smd rect
			(at 0 0.889)
			(size 0.508 0.508)
			(layers "F.Cu" "F.Mask" "F.Paste")
			(net "SMB_VR_STBY_LVC3_SCL")
		)
		(zone
			(layer "F.Cu")
			(hatch none 0.5)
			(connect_pads
				(clearance 0)
			)
			(min_thickness 0.25)
			(keepout
				(tracks allowed)
				(vias not_allowed)
				(pads allowed)
				(copperpour not_allowed)
				(footprints allowed)
			)
			(placement
				(enabled no)
				(sheetname "")
			)
			(fill
				(thermal_gap 0.5)
				(thermal_bridge_width 0.5)
				(island_removal_mode 0)
			)
			(polygon
				(pts
					(xy 417.2966 -18.4912) (xy 417.8046 -18.4912) (xy 417.8046 -18.1102) (xy 417.2966 -18.1102)
				)
			)
		)
		(zone
			(layer "F.Cu")
			(hatch none 0.5)
			(connect_pads
				(clearance 0)
			)
			(min_thickness 0.25)
			(keepout
				(tracks not_allowed)
				(vias allowed)
				(pads allowed)
				(copperpour not_allowed)
				(footprints allowed)
			)
			(placement
				(enabled no)
				(sheetname "")
			)
			(fill
				(thermal_gap 0.5)
				(thermal_bridge_width 0.5)
				(island_removal_mode 0)
			)
			(polygon
				(pts
					(xy 417.2966 -18.1102) (xy 417.8046 -18.1102) (xy 417.8046 -18.4912) (xy 417.2966 -18.4912)
				)
			)
		)
	)
	(footprint ""
		(layer "F.Cu")
		(at 389.128 -88.2015)
		(property "Reference" "R8C26"
			(at 0 0 0)
			(layer "F.SilkS")
			(hide yes)
			(effects
				(font
					(size 1.27 1.27)
				)
			)
		)
		(property "Value" ""
			(at 0 0 0)
			(layer "F.Fab")
			(effects
				(font
					(size 1.27 1.27)
				)
			)
		)
		(duplicate_pad_numbers_are_jumpers no)
		(fp_poly
			(pts
				(xy -0.2794 -0.1016) (xy 0.2794 -0.1016) (xy 0.2794 0.9906) (xy -0.2794 0.9906)
			)
			(stroke
				(width 0)
				(type default)
			)
			(fill no)
			(layer "F.CrtYd")
		)
		(fp_line
			(start -0.2794 -0.1016)
			(end -0.2794 0.9906)
			(stroke
				(width 0.1)
				(type default)
			)
			(layer "F.Fab")
		)
		(fp_line
			(start -0.2794 0.9906)
			(end 0.2794 0.9906)
			(stroke
				(width 0.1)
				(type default)
			)
			(layer "F.Fab")
		)
		(fp_line
			(start 0.2794 -0.1016)
			(end -0.2794 -0.1016)
			(stroke
				(width 0.1)
				(type default)
			)
			(layer "F.Fab")
		)
		(fp_line
			(start 0.2794 0.9906)
			(end 0.2794 -0.1016)
			(stroke
				(width 0.1)
				(type default)
			)
			(layer "F.Fab")
		)
		(pad "1" smd rect
			(at 0 0)
			(size 0.508 0.508)
			(layers "F.Cu" "F.Mask" "F.Paste")
			(net "A_1P8_3P3_RCOMP")
		)
		(pad "2" smd rect
			(at 0 0.889)
			(size 0.508 0.508)
			(layers "F.Cu" "F.Mask" "F.Paste")
			(net "GND")
		)
		(zone
			(layer "F.Cu")
			(hatch none 0.5)
			(connect_pads
				(clearance 0)
			)
			(min_thickness 0.25)
			(keepout
				(tracks allowed)
				(vias not_allowed)
				(pads allowed)
				(copperpour not_allowed)
				(footprints allowed)
			)
			(placement
				(enabled no)
				(sheetname "")
			)
			(fill
				(thermal_gap 0.5)
				(thermal_bridge_width 0.5)
				(island_removal_mode 0)
			)
			(polygon
				(pts
					(xy 388.874 -87.9475) (xy 389.382 -87.9475) (xy 389.382 -87.5665) (xy 388.874 -87.5665)
				)
			)
		)
		(zone
			(layer "F.Cu")
			(hatch none 0.5)
			(connect_pads
				(clearance 0)
			)
			(min_thickness 0.25)
			(keepout
				(tracks not_allowed)
				(vias allowed)
				(pads allowed)
				(copperpour not_allowed)
				(footprints allowed)
			)
			(placement
				(enabled no)
				(sheetname "")
			)
			(fill
				(thermal_gap 0.5)
				(thermal_bridge_width 0.5)
				(island_removal_mode 0)
			)
			(polygon
				(pts
					(xy 388.874 -87.5665) (xy 389.382 -87.5665) (xy 389.382 -87.9475) (xy 388.874 -87.9475)
				)
			)
		)
	)
	(footprint ""
		(layer "F.Cu")
		(at 337.439 -24.1554 90)
		(property "Reference" "R7F11"
			(at 0 0 90)
			(layer "F.SilkS")
			(hide yes)
			(effects
				(font
					(size 1.27 1.27)
				)
			)
		)
		(property "Value" ""
			(at 0 0 90)
			(layer "F.Fab")
			(effects
				(font
					(size 1.27 1.27)
				)
			)
		)
		(duplicate_pad_numbers_are_jumpers no)
		(fp_rect
			(start -0.2794 0.9906)
			(end 0.2794 -0.1016)
			(stroke
				(width 0)
				(type default)
			)
			(fill no)
			(layer "F.CrtYd")
		)
		(fp_line
			(start 0.2794 -0.1016)
			(end -0.2794 -0.1016)
			(stroke
				(width 0.1)
				(type default)
			)
			(layer "F.Fab")
		)
		(fp_line
			(start -0.2794 -0.1016)
			(end -0.2794 0.9906)
			(stroke
				(width 0.1)
				(type default)
			)
			(layer "F.Fab")
		)
		(fp_line
			(start 0.2794 0.9906)
			(end 0.2794 -0.1016)
			(stroke
				(width 0.1)
				(type default)
			)
			(layer "F.Fab")
		)
		(fp_line
			(start -0.2794 0.9906)
			(end 0.2794 0.9906)
			(stroke
				(width 0.1)
				(type default)
			)
			(layer "F.Fab")
		)
		(pad "1" smd rect
			(at 0 0 90)
			(size 0.508 0.508)
			(layers "F.Cu" "F.Mask" "F.Paste")
			(net "VR_FB_PVPP_ABC")
		)
		(pad "2" smd rect
			(at 0 0.889 90)
			(size 0.508 0.508)
			(layers "F.Cu" "F.Mask" "F.Paste")
			(net "AGND_PVPP_ABC")
		)
		(zone
			(layer "F.Cu")
			(hatch none 0.5)
			(connect_pads
				(clearance 0)
			)
			(min_thickness 0.25)
			(keepout
				(tracks not_allowed)
				(vias allowed)
				(pads allowed)
				(copperpour not_allowed)
				(footprints allowed)
			)
			(placement
				(enabled no)
				(sheetname "")
			)
			(fill
				(thermal_gap 0.5)
				(thermal_bridge_width 0.5)
				(island_removal_mode 0)
			)
			(polygon
				(pts
					(xy 338.074 -23.9014) (xy 338.074 -24.4094) (xy 337.693 -24.4094) (xy 337.693 -23.9014)
				)
			)
		)
		(zone
			(layer "F.Cu")
			(hatch none 0.5)
			(connect_pads
				(clearance 0)
			)
			(min_thickness 0.25)
			(keepout
				(tracks allowed)
				(vias not_allowed)
				(pads allowed)
				(copperpour not_allowed)
				(footprints allowed)
			)
			(placement
				(enabled no)
				(sheetname "")
			)
			(fill
				(thermal_gap 0.5)
				(thermal_bridge_width 0.5)
				(island_removal_mode 0)
			)
			(polygon
				(pts
					(xy 338.074 -23.9014) (xy 338.074 -24.4094) (xy 337.693 -24.4094) (xy 337.693 -23.9014)
				)
			)
		)
	)
	(footprint ""
		(layer "F.Cu")
		(at 18.288 -87.7062)
		(property "Reference" "R1D2"
			(at 0 0 0)
			(layer "F.SilkS")
			(hide yes)
			(effects
				(font
					(size 1.27 1.27)
				)
			)
		)
		(property "Value" ""
			(at 0 0 0)
			(layer "F.Fab")
			(effects
				(font
					(size 1.27 1.27)
				)
			)
		)
		(duplicate_pad_numbers_are_jumpers no)
		(fp_rect
			(start -0.2794 0.9906)
			(end 0.2794 -0.1016)
			(stroke
				(width 0)
				(type default)
			)
			(fill no)
			(layer "F.CrtYd")
		)
		(fp_line
			(start -0.2794 -0.1016)
			(end -0.2794 0.9906)
			(stroke
				(width 0.1)
				(type default)
			)
			(layer "F.Fab")
		)
		(fp_line
			(start -0.2794 0.9906)
			(end 0.2794 0.9906)
			(stroke
				(width 0.1)
				(type default)
			)
			(layer "F.Fab")
		)
		(fp_line
			(start 0.2794 -0.1016)
			(end -0.2794 -0.1016)
			(stroke
				(width 0.1)
				(type default)
			)
			(layer "F.Fab")
		)
		(fp_line
			(start 0.2794 0.9906)
			(end 0.2794 -0.1016)
			(stroke
				(width 0.1)
				(type default)
			)
			(layer "F.Fab")
		)
		(pad "1" smd rect
			(at 0 0)
			(size 0.508 0.508)
			(layers "F.Cu" "F.Mask" "F.Paste")
			(net "SVID_VDIO_PVCCIN_CPU1")
		)
		(pad "2" smd rect
			(at 0 0.889)
			(size 0.508 0.508)
			(layers "F.Cu" "F.Mask" "F.Paste")
			(net "SVID_DIO0_CPU1_R")
		)
		(zone
			(layer "F.Cu")
			(hatch none 0.5)
			(connect_pads
				(clearance 0)
			)
			(min_thickness 0.25)
			(keepout
				(tracks not_allowed)
				(vias allowed)
				(pads allowed)
				(copperpour not_allowed)
				(footprints allowed)
			)
			(placement
				(enabled no)
				(sheetname "")
			)
			(fill
				(thermal_gap 0.5)
				(thermal_bridge_width 0.5)
				(island_removal_mode 0)
			)
			(polygon
				(pts
					(xy 18.034 -87.0712) (xy 18.542 -87.0712) (xy 18.542 -87.4522) (xy 18.034 -87.4522)
				)
			)
		)
		(zone
			(layer "F.Cu")
			(hatch none 0.5)
			(connect_pads
				(clearance 0)
			)
			(min_thickness 0.25)
			(keepout
				(tracks allowed)
				(vias not_allowed)
				(pads allowed)
				(copperpour not_allowed)
				(footprints allowed)
			)
			(placement
				(enabled no)
				(sheetname "")
			)
			(fill
				(thermal_gap 0.5)
				(thermal_bridge_width 0.5)
				(island_removal_mode 0)
			)
			(polygon
				(pts
					(xy 18.034 -87.0712) (xy 18.542 -87.0712) (xy 18.542 -87.4522) (xy 18.034 -87.4522)
				)
			)
		)
	)
	(footprint ""
		(layer "F.Cu")
		(at 348.2086 -149.112224 -90)
		(property "Reference" "C7A25"
			(at 0 0 270)
			(layer "F.SilkS")
			(hide yes)
			(effects
				(font
					(size 1.27 1.27)
				)
			)
		)
		(property "Value" ""
			(at 0 0 270)
			(layer "F.Fab")
			(effects
				(font
					(size 1.27 1.27)
				)
			)
		)
		(duplicate_pad_numbers_are_jumpers no)
		(fp_poly
			(pts
				(xy 0.3048 -0.1016) (xy 0.3048 0.9906) (xy -0.3048 0.9906) (xy -0.3048 -0.1016)
			)
			(stroke
				(width 0)
				(type default)
			)
			(fill no)
			(layer "F.CrtYd")
		)
		(fp_line
			(start -0.3048 0.9906)
			(end 0.3048 0.9906)
			(stroke
				(width 0.1)
				(type default)
			)
			(layer "F.Fab")
		)
		(fp_line
			(start 0.3048 0.9906)
			(end 0.3048 -0.1016)
			(stroke
				(width 0.1)
				(type default)
			)
			(layer "F.Fab")
		)
		(fp_line
			(start -0.3048 -0.1016)
			(end -0.3048 0.9906)
			(stroke
				(width 0.1)
				(type default)
			)
			(layer "F.Fab")
		)
		(fp_line
			(start 0.3048 -0.1016)
			(end -0.3048 -0.1016)
			(stroke
				(width 0.1)
				(type default)
			)
			(layer "F.Fab")
		)
		(pad "1" smd rect
			(at 0 0 270)
			(size 0.508 0.508)
			(layers "F.Cu" "F.Mask" "F.Paste")
			(net "P5V_STBY")
		)
		(pad "2" smd rect
			(at 0 0.889 270)
			(size 0.508 0.508)
			(layers "F.Cu" "F.Mask" "F.Paste")
			(net "GND")
		)
		(zone
			(layer "F.Cu")
			(hatch none 0.5)
			(connect_pads
				(clearance 0)
			)
			(min_thickness 0.25)
			(keepout
				(tracks not_allowed)
				(vias allowed)
				(pads allowed)
				(copperpour not_allowed)
				(footprints allowed)
			)
			(placement
				(enabled no)
				(sheetname "")
			)
			(fill
				(thermal_gap 0.5)
				(thermal_bridge_width 0.5)
				(island_removal_mode 0)
			)
			(polygon
				(pts
					(xy 347.5736 -149.366224) (xy 347.5736 -148.858224) (xy 347.9546 -148.858224) (xy 347.9546 -149.366224)
				)
			)
		)
		(zone
			(layer "F.Cu")
			(hatch none 0.5)
			(connect_pads
				(clearance 0)
			)
			(min_thickness 0.25)
			(keepout
				(tracks allowed)
				(vias not_allowed)
				(pads allowed)
				(copperpour not_allowed)
				(footprints allowed)
			)
			(placement
				(enabled no)
				(sheetname "")
			)
			(fill
				(thermal_gap 0.5)
				(thermal_bridge_width 0.5)
				(island_removal_mode 0)
			)
			(polygon
				(pts
					(xy 347.9546 -149.366224) (xy 347.9546 -148.858224) (xy 347.5736 -148.858224) (xy 347.5736 -149.366224)
				)
			)
		)
	)
)
